(kicad_pcb
	(version 20260206)
	(generator "pcbnew")
	(generator_version "10.0")
	(general
		(thickness 1.6)
		(legacy_teardrops no)
	)
	(paper "A4")
	(title_block
		(title "Wiwynn_Tioga_Pass_MB.brd")
		(comment 1 "Tioga Pass / footprints 1184-1190 of 4770")
	)
	(layers
		(0 "F.Cu" signal "TOP")
		(4 "In1.Cu" signal "L2GND")
		(6 "In2.Cu" signal "L3")
		(8 "In3.Cu" signal "L4GND")
		(10 "In4.Cu" signal "L5")
		(12 "In5.Cu" signal "L6GND")
		(14 "In6.Cu" signal "L7VCC")
		(16 "In7.Cu" signal "L8VCC")
		(18 "In8.Cu" signal "L9GND")
		(20 "In9.Cu" signal "L10")
		(22 "In10.Cu" signal "L11GND")
		(24 "In11.Cu" signal "L12")
		(26 "In12.Cu" signal "L13GND")
		(2 "B.Cu" signal "BOTTOM")
		(9 "F.Adhes" user "F.Adhesive")
		(11 "B.Adhes" user "B.Adhesive")
		(13 "F.Paste" user "Package Geometry/Pastemask Top")
		(15 "B.Paste" user "Package Geometry/Pastemask Bottom")
		(5 "F.SilkS" user "Ref Des/Silkscreen Top")
		(7 "B.SilkS" user "Ref Des/Silkscreen Bottom")
		(1 "F.Mask" user "Board Geometry/Soldermask Top")
		(3 "B.Mask" user "Board Geometry/Soldermask Bottom")
		(17 "Dwgs.User" user "User.Drawings")
		(19 "Cmts.User" user "User.Comments")
		(21 "Eco1.User" user "User.Eco1")
		(23 "Eco2.User" user "User.Eco2")
		(25 "Edge.Cuts" user "Board Geometry/Outline")
		(27 "Margin" user)
		(31 "F.CrtYd" user "Package Geometry/Place Bound Top")
		(29 "B.CrtYd" user "Package Geometry/Place Bound Bottom")
		(35 "F.Fab" user "Ref Des/Assembly Top")
		(33 "B.Fab" user "Ref Des/Assembly Bottom")
	)
	(footprint ""
		(layer "F.Cu")
		(at 451.612 -25.4254 90)
		(property "Reference" "C9W13"
			(at 1.47828 0.78994 0)
			(unlocked yes)
			(layer "F.SilkS")
			(effects
				(font
					(size 0.4064 0.254)
					(thickness 0.1524)
				)
			)
		)
		(property "Value" ""
			(at 0 0 90)
			(layer "F.Fab")
			(effects
				(font
					(size 1.27 1.27)
				)
			)
		)
		(duplicate_pad_numbers_are_jumpers no)
		(fp_poly
			(pts
				(xy -0.7239 -0.2159) (xy 0.7239 -0.2159) (xy 0.7239 1.9939) (xy -0.7239 1.9939)
			)
			(stroke
				(width 0)
				(type default)
			)
			(fill no)
			(layer "F.CrtYd")
		)
		(fp_line
			(start 0.7239 -0.2159)
			(end -0.7239 -0.2159)
			(stroke
				(width 0.1)
				(type default)
			)
			(layer "F.Fab")
		)
		(fp_line
			(start -0.7239 -0.2159)
			(end -0.7239 1.9939)
			(stroke
				(width 0.1)
				(type default)
			)
			(layer "F.Fab")
		)
		(fp_line
			(start 0.7239 1.9939)
			(end 0.7239 -0.2159)
			(stroke
				(width 0.1)
				(type default)
			)
			(layer "F.Fab")
		)
		(fp_line
			(start -0.7239 1.9939)
			(end 0.7239 1.9939)
			(stroke
				(width 0.1)
				(type default)
			)
			(layer "F.Fab")
		)
		(pad "1" smd rect
			(at 0 0 90)
			(size 1.27 1.016)
			(layers "F.Cu" "F.Mask" "F.Paste")
			(net "P2V5_AUX_BMC")
		)
		(pad "2" smd rect
			(at 0 1.778 90)
			(size 1.27 1.016)
			(layers "F.Cu" "F.Mask" "F.Paste")
			(net "GND")
		)
		(zone
			(layer "F.Cu")
			(hatch none 0.5)
			(connect_pads
				(clearance 0)
			)
			(min_thickness 0.25)
			(keepout
				(tracks not_allowed)
				(vias allowed)
				(pads allowed)
				(copperpour not_allowed)
				(footprints allowed)
			)
			(placement
				(enabled no)
				(sheetname "")
			)
			(fill
				(thermal_gap 0.5)
				(thermal_bridge_width 0.5)
				(island_removal_mode 0)
			)
			(polygon
				(pts
					(xy 452.12 -24.7904) (xy 452.12 -26.0604) (xy 452.882 -26.0604) (xy 452.882 -24.7904)
				)
			)
		)
	)
	(footprint ""
		(layer "F.Cu")
		(at 455.40549 -34.744406 90)
		(property "Reference" "Q9E1"
			(at 3.81 -0.98933 90)
			(unlocked yes)
			(layer "F.SilkS")
			(effects
				(font
					(size 0.7874 0.5842)
					(thickness 0.1524)
				)
				(justify left)
			)
		)
		(property "Value" ""
			(at 0 0 90)
			(layer "F.Fab")
			(effects
				(font
					(size 1.27 1.27)
				)
			)
		)
		(duplicate_pad_numbers_are_jumpers no)
		(fp_circle
			(center -0.844804 -0.416052)
			(end -0.844804 -0.289052)
			(stroke
				(width 0.254)
				(type default)
			)
			(fill no)
			(layer "F.SilkS")
		)
		(fp_poly
			(pts
				(xy 0.2159 1.7526) (xy 1.5621 1.7526) (xy 1.5621 -0.4572) (xy 0.2159 -0.4572)
			)
			(stroke
				(width 0)
				(type default)
			)
			(fill no)
			(layer "F.CrtYd")
		)
		(fp_line
			(start 1.5621 -0.45466)
			(end 0.2159 -0.45466)
			(stroke
				(width 0.1)
				(type default)
			)
			(layer "F.Fab")
		)
		(fp_line
			(start 0.2159 -0.45466)
			(end 0.2159 1.75514)
			(stroke
				(width 0.1)
				(type default)
			)
			(layer "F.Fab")
		)
		(fp_line
			(start 1.5621 1.75514)
			(end 1.5621 -0.45466)
			(stroke
				(width 0.1)
				(type default)
			)
			(layer "F.Fab")
		)
		(fp_line
			(start 0.2159 1.75514)
			(end 1.5621 1.75514)
			(stroke
				(width 0.1)
				(type default)
			)
			(layer "F.Fab")
		)
		(fp_circle
			(center -0.508 -0.7874)
			(end -0.508 -0.6604)
			(stroke
				(width 0.254)
				(type default)
			)
			(fill no)
			(layer "F.Fab")
		)
		(pad "1" smd rect
			(at 0 0 90)
			(size 1.016 0.381)
			(layers "F.Cu" "F.Mask" "F.Paste")
			(net "GND")
		)
		(pad "2" smd rect
			(at 0 0.65024 90)
			(size 1.016 0.381)
			(layers "F.Cu" "F.Mask" "F.Paste")
			(net "FM_BMC_HEARTBEAT_N")
		)
		(pad "3" smd rect
			(at 0 1.30048 90)
			(size 1.016 0.381)
			(layers "F.Cu" "F.Mask" "F.Paste")
			(net "FM_HEARTBEAT_LED_K")
		)
		(pad "4" smd rect
			(at 1.778 1.30048 90)
			(size 1.016 0.381)
			(layers "F.Cu" "F.Mask" "F.Paste")
			(net "GND")
		)
		(pad "5" smd rect
			(at 1.778 0.65024 90)
			(size 1.016 0.381)
			(layers "F.Cu" "F.Mask" "F.Paste")
			(net "FM_HEARTBEAT_LED")
		)
		(pad "6" smd rect
			(at 1.778 0 90)
			(size 1.016 0.381)
			(layers "F.Cu" "F.Mask" "F.Paste")
			(net "FM_HEARTBEAT_LED")
		)
		(zone
			(layer "F.Cu")
			(hatch none 0.5)
			(connect_pads
				(clearance 0)
			)
			(min_thickness 0.25)
			(keepout
				(tracks allowed)
				(vias not_allowed)
				(pads allowed)
				(copperpour not_allowed)
				(footprints allowed)
			)
			(placement
				(enabled no)
				(sheetname "")
			)
			(fill
				(thermal_gap 0.5)
				(thermal_bridge_width 0.5)
				(island_removal_mode 0)
			)
			(polygon
				(pts
					(xy 455.21499 -36.014406) (xy 455.21499 -37.030406) (xy 456.90409 -37.030406) (xy 456.90409 -36.014406)
				)
			)
		)
		(zone
			(layer "F.Cu")
			(hatch none 0.5)
			(connect_pads
				(clearance 0)
			)
			(min_thickness 0.25)
			(keepout
				(tracks allowed)
				(vias not_allowed)
				(pads allowed)
				(copperpour not_allowed)
				(footprints allowed)
			)
			(placement
				(enabled no)
				(sheetname "")
			)
			(fill
				(thermal_gap 0.5)
				(thermal_bridge_width 0.5)
				(island_removal_mode 0)
			)
			(polygon
				(pts
					(xy 455.21499 -34.236406) (xy 455.21499 -35.252406) (xy 456.90409 -35.252406) (xy 456.90409 -34.236406)
				)
			)
		)
	)
	(footprint ""
		(layer "F.Cu")
		(at 479.19386 -18.48739)
		(property "Reference" "C9G5"
			(at 0 0 0)
			(layer "F.SilkS")
			(hide yes)
			(effects
				(font
					(size 1.27 1.27)
				)
			)
		)
		(property "Value" ""
			(at 0 0 0)
			(layer "F.Fab")
			(effects
				(font
					(size 1.27 1.27)
				)
			)
		)
		(duplicate_pad_numbers_are_jumpers no)
		(fp_poly
			(pts
				(xy 0.3048 -0.1016) (xy 0.3048 0.9906) (xy -0.3048 0.9906) (xy -0.3048 -0.1016)
			)
			(stroke
				(width 0)
				(type default)
			)
			(fill no)
			(layer "F.CrtYd")
		)
		(fp_line
			(start -0.3048 -0.1016)
			(end -0.3048 0.9906)
			(stroke
				(width 0.1)
				(type default)
			)
			(layer "F.Fab")
		)
		(fp_line
			(start -0.3048 0.9906)
			(end 0.3048 0.9906)
			(stroke
				(width 0.1)
				(type default)
			)
			(layer "F.Fab")
		)
		(fp_line
			(start 0.3048 -0.1016)
			(end -0.3048 -0.1016)
			(stroke
				(width 0.1)
				(type default)
			)
			(layer "F.Fab")
		)
		(fp_line
			(start 0.3048 0.9906)
			(end 0.3048 -0.1016)
			(stroke
				(width 0.1)
				(type default)
			)
			(layer "F.Fab")
		)
		(pad "1" smd rect
			(at 0 0)
			(size 0.508 0.508)
			(layers "F.Cu" "F.Mask" "F.Paste")
			(net "GND_LAN_TRCT1234_C")
		)
		(pad "2" smd rect
			(at 0 0.889)
			(size 0.508 0.508)
			(layers "F.Cu" "F.Mask" "F.Paste")
			(net "GND")
		)
		(zone
			(layer "F.Cu")
			(hatch none 0.5)
			(connect_pads
				(clearance 0)
			)
			(min_thickness 0.25)
			(keepout
				(tracks allowed)
				(vias not_allowed)
				(pads allowed)
				(copperpour not_allowed)
				(footprints allowed)
			)
			(placement
				(enabled no)
				(sheetname "")
			)
			(fill
				(thermal_gap 0.5)
				(thermal_bridge_width 0.5)
				(island_removal_mode 0)
			)
			(polygon
				(pts
					(xy 478.93986 -18.23339) (xy 479.44786 -18.23339) (xy 479.44786 -17.85239) (xy 478.93986 -17.85239)
				)
			)
		)
		(zone
			(layer "F.Cu")
			(hatch none 0.5)
			(connect_pads
				(clearance 0)
			)
			(min_thickness 0.25)
			(keepout
				(tracks not_allowed)
				(vias allowed)
				(pads allowed)
				(copperpour not_allowed)
				(footprints allowed)
			)
			(placement
				(enabled no)
				(sheetname "")
			)
			(fill
				(thermal_gap 0.5)
				(thermal_bridge_width 0.5)
				(island_removal_mode 0)
			)
			(polygon
				(pts
					(xy 478.93986 -17.85239) (xy 479.44786 -17.85239) (xy 479.44786 -18.23339) (xy 478.93986 -18.23339)
				)
			)
		)
	)
	(footprint ""
		(layer "F.Cu")
		(at 1.651 -143.256 90)
		(property "Reference" "C1A13"
			(at 0 0 90)
			(layer "F.SilkS")
			(hide yes)
			(effects
				(font
					(size 1.27 1.27)
				)
			)
		)
		(property "Value" ""
			(at 0 0 90)
			(layer "F.Fab")
			(effects
				(font
					(size 1.27 1.27)
				)
			)
		)
		(duplicate_pad_numbers_are_jumpers no)
		(fp_rect
			(start 0.3048 0.9906)
			(end -0.3048 -0.1016)
			(stroke
				(width 0)
				(type default)
			)
			(fill no)
			(layer "F.CrtYd")
		)
		(fp_line
			(start 0.3048 -0.1016)
			(end -0.3048 -0.1016)
			(stroke
				(width 0.1)
				(type default)
			)
			(layer "F.Fab")
		)
		(fp_line
			(start -0.3048 -0.1016)
			(end -0.3048 0.9906)
			(stroke
				(width 0.1)
				(type default)
			)
			(layer "F.Fab")
		)
		(fp_line
			(start 0.3048 0.9906)
			(end 0.3048 -0.1016)
			(stroke
				(width 0.1)
				(type default)
			)
			(layer "F.Fab")
		)
		(fp_line
			(start -0.3048 0.9906)
			(end 0.3048 0.9906)
			(stroke
				(width 0.1)
				(type default)
			)
			(layer "F.Fab")
		)
		(pad "1" smd rect
			(at 0 0 90)
			(size 0.508 0.508)
			(layers "F.Cu" "F.Mask" "F.Paste")
			(net "P5V_STBY")
		)
		(pad "2" smd rect
			(at 0 0.889 90)
			(size 0.508 0.508)
			(layers "F.Cu" "F.Mask" "F.Paste")
			(net "GND")
		)
		(zone
			(layer "F.Cu")
			(hatch none 0.5)
			(connect_pads
				(clearance 0)
			)
			(min_thickness 0.25)
			(keepout
				(tracks not_allowed)
				(vias allowed)
				(pads allowed)
				(copperpour not_allowed)
				(footprints allowed)
			)
			(placement
				(enabled no)
				(sheetname "")
			)
			(fill
				(thermal_gap 0.5)
				(thermal_bridge_width 0.5)
				(island_removal_mode 0)
			)
			(polygon
				(pts
					(xy 2.286 -143.51) (xy 1.905 -143.51) (xy 1.905 -143.002) (xy 2.286 -143.002)
				)
			)
		)
		(zone
			(layer "F.Cu")
			(hatch none 0.5)
			(connect_pads
				(clearance 0)
			)
			(min_thickness 0.25)
			(keepout
				(tracks allowed)
				(vias not_allowed)
				(pads allowed)
				(copperpour not_allowed)
				(footprints allowed)
			)
			(placement
				(enabled no)
				(sheetname "")
			)
			(fill
				(thermal_gap 0.5)
				(thermal_bridge_width 0.5)
				(island_removal_mode 0)
			)
			(polygon
				(pts
					(xy 2.286 -143.51) (xy 1.905 -143.51) (xy 1.905 -143.002) (xy 2.286 -143.002)
				)
			)
		)
	)
	(footprint ""
		(layer "F.Cu")
		(at 347.850206 -2.254504 90)
		(property "Reference" "C7G40"
			(at 0 0 90)
			(layer "F.SilkS")
			(hide yes)
			(effects
				(font
					(size 1.27 1.27)
				)
			)
		)
		(property "Value" ""
			(at 0 0 90)
			(layer "F.Fab")
			(effects
				(font
					(size 1.27 1.27)
				)
			)
		)
		(duplicate_pad_numbers_are_jumpers no)
		(fp_poly
			(pts
				(xy 0.3048 -0.1016) (xy 0.3048 0.9906) (xy -0.3048 0.9906) (xy -0.3048 -0.1016)
			)
			(stroke
				(width 0)
				(type default)
			)
			(fill no)
			(layer "F.CrtYd")
		)
		(fp_line
			(start 0.3048 -0.1016)
			(end -0.3048 -0.1016)
			(stroke
				(width 0.1)
				(type default)
			)
			(layer "F.Fab")
		)
		(fp_line
			(start -0.3048 -0.1016)
			(end -0.3048 0.9906)
			(stroke
				(width 0.1)
				(type default)
			)
			(layer "F.Fab")
		)
		(fp_line
			(start 0.3048 0.9906)
			(end 0.3048 -0.1016)
			(stroke
				(width 0.1)
				(type default)
			)
			(layer "F.Fab")
		)
		(fp_line
			(start -0.3048 0.9906)
			(end 0.3048 0.9906)
			(stroke
				(width 0.1)
				(type default)
			)
			(layer "F.Fab")
		)
		(pad "1" smd rect
			(at 0 0 90)
			(size 0.508 0.508)
			(layers "F.Cu" "F.Mask" "F.Paste")
			(net "VR_PVDDQ_ABC_PH2_VCIN")
		)
		(pad "2" smd rect
			(at 0 0.889 90)
			(size 0.508 0.508)
			(layers "F.Cu" "F.Mask" "F.Paste")
			(net "GND")
		)
		(zone
			(layer "F.Cu")
			(hatch none 0.5)
			(connect_pads
				(clearance 0)
			)
			(min_thickness 0.25)
			(keepout
				(tracks allowed)
				(vias not_allowed)
				(pads allowed)
				(copperpour not_allowed)
				(footprints allowed)
			)
			(placement
				(enabled no)
				(sheetname "")
			)
			(fill
				(thermal_gap 0.5)
				(thermal_bridge_width 0.5)
				(island_removal_mode 0)
			)
			(polygon
				(pts
					(xy 348.104206 -2.000504) (xy 348.104206 -2.508504) (xy 348.485206 -2.508504) (xy 348.485206 -2.000504)
				)
			)
		)
		(zone
			(layer "F.Cu")
			(hatch none 0.5)
			(connect_pads
				(clearance 0)
			)
			(min_thickness 0.25)
			(keepout
				(tracks not_allowed)
				(vias allowed)
				(pads allowed)
				(copperpour not_allowed)
				(footprints allowed)
			)
			(placement
				(enabled no)
				(sheetname "")
			)
			(fill
				(thermal_gap 0.5)
				(thermal_bridge_width 0.5)
				(island_removal_mode 0)
			)
			(polygon
				(pts
					(xy 348.485206 -2.000504) (xy 348.485206 -2.508504) (xy 348.104206 -2.508504) (xy 348.104206 -2.000504)
				)
			)
		)
	)
	(footprint ""
		(layer "F.Cu")
		(at 195.165218 -86.502748)
		(property "Reference" "CT36"
			(at -4.29387 -6.096 270)
			(unlocked yes)
			(layer "F.SilkS")
			(effects
				(font
					(size 0.7874 0.5842)
					(thickness 0.1524)
				)
				(justify left)
			)
		)
		(property "Value" ""
			(at 0 0 0)
			(layer "F.Fab")
			(effects
				(font
					(size 1.27 1.27)
				)
			)
		)
		(duplicate_pad_numbers_are_jumpers no)
		(fp_poly
			(pts
				(xy 0.3048 -0.1016) (xy 0.3048 0.9906) (xy -0.3048 0.9906) (xy -0.3048 -0.1016)
			)
			(stroke
				(width 0)
				(type default)
			)
			(fill no)
			(layer "F.CrtYd")
		)
		(fp_line
			(start -0.3048 -0.1016)
			(end -0.3048 0.9906)
			(stroke
				(width 0.1)
				(type default)
			)
			(layer "F.Fab")
		)
		(fp_line
			(start -0.3048 0.9906)
			(end 0.3048 0.9906)
			(stroke
				(width 0.1)
				(type default)
			)
			(layer "F.Fab")
		)
		(fp_line
			(start 0.3048 -0.1016)
			(end -0.3048 -0.1016)
			(stroke
				(width 0.1)
				(type default)
			)
			(layer "F.Fab")
		)
		(fp_line
			(start 0.3048 0.9906)
			(end 0.3048 -0.1016)
			(stroke
				(width 0.1)
				(type default)
			)
			(layer "F.Fab")
		)
		(pad "1" smd rect
			(at 0 0)
			(size 0.508 0.508)
			(layers "F.Cu" "F.Mask" "F.Paste")
			(net "VR_PVCCIN_CPU0_AIREF5")
		)
		(pad "2" smd rect
			(at 0 0.889)
			(size 0.508 0.508)
			(layers "F.Cu" "F.Mask" "F.Paste")
			(net "GND")
		)
		(zone
			(layer "F.Cu")
			(hatch none 0.5)
			(connect_pads
				(clearance 0)
			)
			(min_thickness 0.25)
			(keepout
				(tracks allowed)
				(vias not_allowed)
				(pads allowed)
				(copperpour not_allowed)
				(footprints allowed)
			)
			(placement
				(enabled no)
				(sheetname "")
			)
			(fill
				(thermal_gap 0.5)
				(thermal_bridge_width 0.5)
				(island_removal_mode 0)
			)
			(polygon
				(pts
					(xy 194.911218 -86.248748) (xy 195.419218 -86.248748) (xy 195.419218 -85.867748) (xy 194.911218 -85.867748)
				)
			)
		)
		(zone
			(layer "F.Cu")
			(hatch none 0.5)
			(connect_pads
				(clearance 0)
			)
			(min_thickness 0.25)
			(keepout
				(tracks not_allowed)
				(vias allowed)
				(pads allowed)
				(copperpour not_allowed)
				(footprints allowed)
			)
			(placement
				(enabled no)
				(sheetname "")
			)
			(fill
				(thermal_gap 0.5)
				(thermal_bridge_width 0.5)
				(island_removal_mode 0)
			)
			(polygon
				(pts
					(xy 194.911218 -85.867748) (xy 195.419218 -85.867748) (xy 195.419218 -86.248748) (xy 194.911218 -86.248748)
				)
			)
		)
	)
	(footprint ""
		(layer "F.Cu")
		(at 178.054 -77.978)
		(property "Reference" "R4D24"
			(at 0 0 0)
			(layer "F.SilkS")
			(hide yes)
			(effects
				(font
					(size 1.27 1.27)
				)
			)
		)
		(property "Value" ""
			(at 0 0 0)
			(layer "F.Fab")
			(effects
				(font
					(size 1.27 1.27)
				)
			)
		)
		(duplicate_pad_numbers_are_jumpers no)
		(fp_poly
			(pts
				(xy -0.2794 -0.1016) (xy 0.2794 -0.1016) (xy 0.2794 0.9906) (xy -0.2794 0.9906)
			)
			(stroke
				(width 0)
				(type default)
			)
			(fill no)
			(layer "F.CrtYd")
		)
		(fp_line
			(start -0.2794 -0.1016)
			(end -0.2794 0.9906)
			(stroke
				(width 0.1)
				(type default)
			)
			(layer "F.Fab")
		)
		(fp_line
			(start -0.2794 0.9906)
			(end 0.2794 0.9906)
			(stroke
				(width 0.1)
				(type default)
			)
			(layer "F.Fab")
		)
		(fp_line
			(start 0.2794 -0.1016)
			(end -0.2794 -0.1016)
			(stroke
				(width 0.1)
				(type default)
			)
			(layer "F.Fab")
		)
		(fp_line
			(start 0.2794 0.9906)
			(end 0.2794 -0.1016)
			(stroke
				(width 0.1)
				(type default)
			)
			(layer "F.Fab")
		)
		(pad "1" smd rect
			(at 0 0)
			(size 0.508 0.508)
			(layers "F.Cu" "F.Mask" "F.Paste")
			(net "CLK_100M_CPU0_BCLK1_DP")
		)
		(pad "2" smd rect
			(at 0 0.889)
			(size 0.508 0.508)
			(layers "F.Cu" "F.Mask" "F.Paste")
			(net "GND")
		)
		(zone
			(layer "F.Cu")
			(hatch none 0.5)
			(connect_pads
				(clearance 0)
			)
			(min_thickness 0.25)
			(keepout
				(tracks allowed)
				(vias not_allowed)
				(pads allowed)
				(copperpour not_allowed)
				(footprints allowed)
			)
			(placement
				(enabled no)
				(sheetname "")
			)
			(fill
				(thermal_gap 0.5)
				(thermal_bridge_width 0.5)
				(island_removal_mode 0)
			)
			(polygon
				(pts
					(xy 177.8 -77.724) (xy 178.308 -77.724) (xy 178.308 -77.343) (xy 177.8 -77.343)
				)
			)
		)
		(zone
			(layer "F.Cu")
			(hatch none 0.5)
			(connect_pads
				(clearance 0)
			)
			(min_thickness 0.25)
			(keepout
				(tracks not_allowed)
				(vias allowed)
				(pads allowed)
				(copperpour not_allowed)
				(footprints allowed)
			)
			(placement
				(enabled no)
				(sheetname "")
			)
			(fill
				(thermal_gap 0.5)
				(thermal_bridge_width 0.5)
				(island_removal_mode 0)
			)
			(polygon
				(pts
					(xy 177.8 -77.343) (xy 178.308 -77.343) (xy 178.308 -77.724) (xy 177.8 -77.724)
				)
			)
		)
	)
)
